# S9S_MB_2U (Grand Teton) — schematic netlist excerpt (pin names and nets, part order shuffled) for the footprints in the layout excerpt that follows; sources: Cadence DE-HDL packaged netlist, KiCad conversion of 03242023_DA0F0TMBIJ0_F0T_Motherboard_J_brd_V01_OCP.brd

R699  Q_RES  33.2 1% CHIP  pkg 0402LF  page 183 : A = FM_PCH_CRASHLOG_TRIG_R_N ; B = FM_PCH_CRASHLOG_TRIG_N
R2976  Q_RES  10K 1% EMPTY  pkg 0402LF  page 195 : A = P1V05_PCH_AUX ; B = FM_BOARD_SKU_ID3

DB1  TDR_3P  EMPTY  pkg TH2  page 309
  GND  = T1_GND
  IO1  = TDR_SE_40_OHM_TOP
  IO2  = TDR_SE_40_OHM_TOP

(kicad_pcb
	(version 20260206)
	(generator "pcbnew")
	(generator_version "10.0")
	(general
		(thickness 1.6)
		(legacy_teardrops no)
	)
	(paper "A4")
	(title_block
		(title "03242023_DA0F0TMBIJ0_F0T_Motherboard_J_brd_V01_OCP.brd")
		(comment 1 "Grand Teton / footprints 2626-2628 of 6105")
	)
	(layers
		(0 "F.Cu" signal "TOP")
		(4 "In1.Cu" signal "GND")
		(6 "In2.Cu" signal "IN1")
		(8 "In3.Cu" signal "GND1")
		(10 "In4.Cu" signal "IN2")
		(12 "In5.Cu" signal "GND2")
		(14 "In6.Cu" signal "IN3")
		(16 "In7.Cu" signal "GND3")
		(18 "In8.Cu" signal "VCC")
		(20 "In9.Cu" signal "VCC1")
		(22 "In10.Cu" signal "GND4")
		(24 "In11.Cu" signal "IN4")
		(26 "In12.Cu" signal "GND5")
		(28 "In13.Cu" signal "IN5")
		(30 "In14.Cu" signal "GND6")
		(32 "In15.Cu" signal "IN6")
		(34 "In16.Cu" signal "GND7")
		(2 "B.Cu" signal "BOTTOM")
		(9 "F.Adhes" user "F.Adhesive")
		(11 "B.Adhes" user "B.Adhesive")
		(13 "F.Paste" user "Package Geometry/Pastemask Top")
		(15 "B.Paste" user "Package Geometry/Pastemask Bottom")
		(5 "F.SilkS" user "Ref Des/Silkscreen Top")
		(7 "B.SilkS" user "Ref Des/Silkscreen Bottom")
		(1 "F.Mask" user "Board Geometry/Soldermask Top")
		(3 "B.Mask" user "Board Geometry/Soldermask Bottom")
		(17 "Dwgs.User" user "User.Drawings")
		(19 "Cmts.User" user "User.Comments")
		(21 "Eco1.User" user "User.Eco1")
		(23 "Eco2.User" user "User.Eco2")
		(25 "Edge.Cuts" user "Board Geometry/Outline")
		(27 "Margin" user)
		(31 "F.CrtYd" user "Package Geometry/Place Bound Top")
		(29 "B.CrtYd" user "Package Geometry/Place Bound Bottom")
		(35 "F.Fab" user "Ref Des/Assembly Top")
		(33 "B.Fab" user "Ref Des/Assembly Bottom")
	)
	(footprint ""
		(layer "F.Cu")
		(at 315.10224 -48.584866)
		(property "Reference" "R699"
			(at 0 0 0)
			(layer "F.SilkS")
			(hide yes)
			(effects
				(font
					(size 1.27 1.27)
				)
			)
		)
		(property "Value" ""
			(at 0 0 0)
			(layer "F.Fab")
			(effects
				(font
					(size 1.27 1.27)
				)
			)
		)
		(duplicate_pad_numbers_are_jumpers no)
		(fp_line
			(start -0.7874 -0.4064)
			(end 0.7874 -0.4064)
			(stroke
				(width 0.1524)
				(type default)
			)
			(layer "F.SilkS")
		)
		(fp_line
			(start -0.7874 0.4064)
			(end -0.7874 -0.4064)
			(stroke
				(width 0.1524)
				(type default)
			)
			(layer "F.SilkS")
		)
		(fp_line
			(start 0.7874 -0.4064)
			(end 0.7874 0.4064)
			(stroke
				(width 0.1524)
				(type default)
			)
			(layer "F.SilkS")
		)
		(fp_line
			(start 0.7874 0.4064)
			(end -0.7874 0.4064)
			(stroke
				(width 0.1524)
				(type default)
			)
			(layer "F.SilkS")
		)
		(fp_line
			(start -0.67945 -0.305054)
			(end -0.12065 -0.305054)
			(stroke
				(width 0.1)
				(type default)
			)
			(layer "F.Fab")
		)
		(fp_line
			(start -0.67945 0.3048)
			(end -0.67945 -0.305054)
			(stroke
				(width 0.1)
				(type default)
			)
			(layer "F.Fab")
		)
		(fp_line
			(start -0.12065 -0.305054)
			(end -0.12065 -0.2794)
			(stroke
				(width 0.1)
				(type default)
			)
			(layer "F.Fab")
		)
		(fp_line
			(start -0.12065 -0.2794)
			(end 0.12065 -0.2794)
			(stroke
				(width 0.1)
				(type default)
			)
			(layer "F.Fab")
		)
		(fp_line
			(start -0.12065 0.2794)
			(end -0.12065 0.3048)
			(stroke
				(width 0.1)
				(type default)
			)
			(layer "F.Fab")
		)
		(fp_line
			(start -0.12065 0.3048)
			(end -0.67945 0.3048)
			(stroke
				(width 0.1)
				(type default)
			)
			(layer "F.Fab")
		)
		(fp_line
			(start 0.120396 0.2794)
			(end -0.12065 0.2794)
			(stroke
				(width 0.1)
				(type default)
			)
			(layer "F.Fab")
		)
		(fp_line
			(start 0.120396 0.3048)
			(end 0.120396 0.2794)
			(stroke
				(width 0.1)
				(type default)
			)
			(layer "F.Fab")
		)
		(fp_line
			(start 0.12065 -0.3048)
			(end 0.67945 -0.3048)
			(stroke
				(width 0.1)
				(type default)
			)
			(layer "F.Fab")
		)
		(fp_line
			(start 0.12065 -0.2794)
			(end 0.12065 -0.3048)
			(stroke
				(width 0.1)
				(type default)
			)
			(layer "F.Fab")
		)
		(fp_line
			(start 0.67945 -0.3048)
			(end 0.67945 0.3048)
			(stroke
				(width 0.1)
				(type default)
			)
			(layer "F.Fab")
		)
		(fp_line
			(start 0.67945 0.3048)
			(end 0.120396 0.3048)
			(stroke
				(width 0.1)
				(type default)
			)
			(layer "F.Fab")
		)
		(pad "1" smd circle
			(at -0.40005 0)
			(size 0 0)
			(layers "F.Cu" "F.Mask" "F.Paste")
			(net "FM_PCH_CRASHLOG_TRIG_R_N")
		)
		(pad "2" smd circle
			(at 0.40005 0)
			(size 0 0)
			(layers "F.Cu" "F.Mask" "F.Paste")
			(net "FM_PCH_CRASHLOG_TRIG_N")
		)
	)
	(footprint ""
		(layer "F.Cu")
		(at 299.02023 -54.400196)
		(property "Reference" "R2976"
			(at 0 0 0)
			(layer "F.SilkS")
			(hide yes)
			(effects
				(font
					(size 1.27 1.27)
				)
			)
		)
		(property "Value" ""
			(at 0 0 0)
			(layer "F.Fab")
			(effects
				(font
					(size 1.27 1.27)
				)
			)
		)
		(duplicate_pad_numbers_are_jumpers no)
		(fp_line
			(start -0.7874 -0.4064)
			(end 0.7874 -0.4064)
			(stroke
				(width 0.1524)
				(type default)
			)
			(layer "F.SilkS")
		)
		(fp_line
			(start -0.7874 0.4064)
			(end -0.7874 -0.4064)
			(stroke
				(width 0.1524)
				(type default)
			)
			(layer "F.SilkS")
		)
		(fp_line
			(start 0.7874 -0.4064)
			(end 0.7874 0.4064)
			(stroke
				(width 0.1524)
				(type default)
			)
			(layer "F.SilkS")
		)
		(fp_line
			(start 0.7874 0.4064)
			(end -0.7874 0.4064)
			(stroke
				(width 0.1524)
				(type default)
			)
			(layer "F.SilkS")
		)
		(fp_line
			(start -0.67945 -0.305054)
			(end -0.12065 -0.305054)
			(stroke
				(width 0.1)
				(type default)
			)
			(layer "F.Fab")
		)
		(fp_line
			(start -0.67945 0.3048)
			(end -0.67945 -0.305054)
			(stroke
				(width 0.1)
				(type default)
			)
			(layer "F.Fab")
		)
		(fp_line
			(start -0.12065 -0.305054)
			(end -0.12065 -0.2794)
			(stroke
				(width 0.1)
				(type default)
			)
			(layer "F.Fab")
		)
		(fp_line
			(start -0.12065 -0.2794)
			(end 0.12065 -0.2794)
			(stroke
				(width 0.1)
				(type default)
			)
			(layer "F.Fab")
		)
		(fp_line
			(start -0.12065 0.2794)
			(end -0.12065 0.3048)
			(stroke
				(width 0.1)
				(type default)
			)
			(layer "F.Fab")
		)
		(fp_line
			(start -0.12065 0.3048)
			(end -0.67945 0.3048)
			(stroke
				(width 0.1)
				(type default)
			)
			(layer "F.Fab")
		)
		(fp_line
			(start 0.120396 0.2794)
			(end -0.12065 0.2794)
			(stroke
				(width 0.1)
				(type default)
			)
			(layer "F.Fab")
		)
		(fp_line
			(start 0.120396 0.3048)
			(end 0.120396 0.2794)
			(stroke
				(width 0.1)
				(type default)
			)
			(layer "F.Fab")
		)
		(fp_line
			(start 0.12065 -0.3048)
			(end 0.67945 -0.3048)
			(stroke
				(width 0.1)
				(type default)
			)
			(layer "F.Fab")
		)
		(fp_line
			(start 0.12065 -0.2794)
			(end 0.12065 -0.3048)
			(stroke
				(width 0.1)
				(type default)
			)
			(layer "F.Fab")
		)
		(fp_line
			(start 0.67945 -0.3048)
			(end 0.67945 0.3048)
			(stroke
				(width 0.1)
				(type default)
			)
			(layer "F.Fab")
		)
		(fp_line
			(start 0.67945 0.3048)
			(end 0.120396 0.3048)
			(stroke
				(width 0.1)
				(type default)
			)
			(layer "F.Fab")
		)
		(pad "1" smd circle
			(at -0.40005 0)
			(size 0 0)
			(layers "F.Cu" "F.Mask" "F.Paste")
			(net "P1V05_PCH_AUX")
		)
		(pad "2" smd circle
			(at 0.40005 0)
			(size 0 0)
			(layers "F.Cu" "F.Mask" "F.Paste")
			(net "FM_BOARD_SKU_ID3")
		)
	)
	(footprint ""
		(layer "F.Cu")
		(at 495.599212 -342.797638)
		(property "Reference" "DB1"
			(at 2.19837 2.397506 90)
			(unlocked yes)
			(layer "F.SilkS")
			(effects
				(font
					(size 0.7874 0.5842)
					(thickness 0.1524)
				)
				(justify left)
			)
		)
		(property "Value" ""
			(at 0 0 0)
			(layer "F.Fab")
			(effects
				(font
					(size 1.27 1.27)
				)
			)
		)
		(duplicate_pad_numbers_are_jumpers no)
		(fp_line
			(start -3.330702 -4.771136)
			(end 3.330702 -4.771136)
			(stroke
				(width 0.1524)
				(type default)
			)
			(layer "F.SilkS")
		)
		(fp_line
			(start 0 4.011168)
			(end -3.330702 -4.771136)
			(stroke
				(width 0.1524)
				(type default)
			)
			(layer "F.SilkS")
		)
		(fp_line
			(start 3.330702 -4.771136)
			(end 0 4.011168)
			(stroke
				(width 0.1524)
				(type default)
			)
			(layer "F.SilkS")
		)
		(fp_line
			(start -3.330702 -4.771136)
			(end 3.330702 -4.771136)
			(stroke
				(width 0.1)
				(type default)
			)
			(layer "F.Fab")
		)
		(fp_line
			(start 0 4.011168)
			(end -3.330702 -4.771136)
			(stroke
				(width 0.1)
				(type default)
			)
			(layer "F.Fab")
		)
		(fp_line
			(start 3.330702 -4.771136)
			(end 0 4.011168)
			(stroke
				(width 0.1)
				(type default)
			)
			(layer "F.Fab")
		)
		(pad "1" thru_hole circle
			(at 0 0)
			(size 2.159 2.159)
			(drill 1.7018)
			(layers "*.Cu" "*.Mask")
			(remove_unused_layers no)
			(net "T1_GND")
			(clearance 0.0254)
			(thermal_gap 0.0254)
		)
		(pad "2" thru_hole circle
			(at -1.27 -3.348736)
			(size 2.159 2.159)
			(drill 1.7018)
			(layers "*.Cu" "*.Mask")
			(remove_unused_layers no)
			(net "TDR_SE_40_OHM_TOP")
			(clearance 0.0254)
			(thermal_gap 0.0254)
		)
		(pad "3" thru_hole circle
			(at 1.27 -3.348736)
			(size 2.159 2.159)
			(drill 1.7018)
			(layers "*.Cu" "*.Mask")
			(remove_unused_layers no)
			(net "TDR_SE_40_OHM_TOP")
			(clearance 0.0254)
			(thermal_gap 0.0254)
		)
	)
)
